#ISCELL
  mstr_misc prelim *
  *
#ISCELL
  mstr_symbols design_note *
  *
#ISCELL
  mstr_symbols intel_corp_bpage *
  *
#ISCELL
  mstr_standard tap *
  page65_i11
#ISCELL
  mstr_standard tap *
  page65_i12
#ISCELL
  mstr_standard tap *
  page65_i13
#ISCELL
  mstr_standard tap *
  page65_i14
#ISCELL
  mstr_standard tap *
  page65_i15
#ISCELL
  mstr_standard tap *
  page65_i16
#ISCELL
  mstr_standard tap *
  page65_i17
#ISCELL
  mstr_standard tap *
  page65_i18
#ISCELL
  mstr_standard tap *
  page65_i19
#ISCELL
  mstr_standard tap *
  page65_i20
#ISCELL
  mstr_standard tap *
  page65_i21
#ISCELL
  mstr_standard tap *
  page65_i22
#ISCELL
  mstr_standard tap *
  page65_i23
#ISCELL
  mstr_standard tap *
  page65_i24
#ISCELL
  mstr_standard tap *
  page65_i25
#ISCELL
  mstr_standard tap *
  page65_i26
#ISCELL
  mstr_standard tap *
  page65_i27
#ISCELL
  mstr_standard tap *
  page65_i28
#ISCELL
  mstr_standard tap *
  page65_i29
#ISCELL
  mstr_standard tap *
  page65_i3
#ISCELL
  mstr_standard tap *
  page65_i30
#ISCELL
  mstr_standard tap *
  page65_i31
#ISCELL
  mstr_standard tap *
  page65_i32
#ISCELL
  mstr_standard tap *
  page65_i33
#ISCELL
  mstr_standard tap *
  page65_i34
#ISCELL
  mstr_standard tap *
  page65_i35
#ISCELL
  mstr_standard tap *
  page65_i36
#ISCELL
  mstr_standard tap *
  page65_i37
#ISCELL
  mstr_standard tap *
  page65_i38
#ISCELL
  mstr_standard tap *
  page65_i39
#ISCELL
  mstr_standard tap *
  page65_i4
#ISCELL
  mstr_standard tap *
  page65_i40
#ISCELL
  mstr_standard tap *
  page65_i41
#ISCELL
  mstr_standard tap *
  page65_i42
#ISCELL
  mstr_standard tap *
  page65_i43
#ISCELL
  mstr_standard tap *
  page65_i44
#ISCELL
  mstr_standard tap *
  page65_i45
#ISCELL
  mstr_standard tap *
  page65_i46
#ISCELL
  mstr_standard tap *
  page65_i47
#ISCELL
  mstr_standard tap *
  page65_i48
#ISCELL
  mstr_standard tap *
  page65_i49
#ISCELL
  mstr_standard tap *
  page65_i5
#ISCELL
  mstr_standard tap *
  page65_i50
#ISCELL
  mstr_standard tap *
  page65_i51
#ISCELL
  mstr_standard tap *
  page65_i52
#ISCELL
  mstr_standard tap *
  page65_i53
#ISCELL
  mstr_standard tap *
  page65_i54
#ISCELL
  mstr_standard tap *
  page65_i55
#ISCELL
  mstr_standard tap *
  page65_i56
#ISCELL
  mstr_standard tap *
  page65_i57
#ISCELL
  mstr_standard tap *
  page65_i58
#ISCELL
  mstr_standard tap *
  page65_i59
#ISCELL
  mstr_standard tap *
  page65_i6
#ISCELL
  mstr_standard tap *
  page65_i60
#ISCELL
  mstr_standard tap *
  page65_i61
#ISCELL
  mstr_standard tap *
  page65_i62
#ISCELL
  mstr_standard tap *
  page65_i63
#ISCELL
  mstr_standard tap *
  page65_i64
#ISCELL
  mstr_standard tap *
  page65_i65
#ISCELL
  mstr_standard tap *
  page65_i66
#ISCELL
  mstr_standard tap *
  page65_i67
#CELL
  chpset_lib skx_ext_b *
  page65_i68
#ISCELL
  mstr_standard tap *
  page65_i7
#ISCELL
  mstr_standard tap *
  page65_i8
#ISCELL
  mstr_standard tap *
  page65_i9
